# T6G (Grand Teton) — schematic netlist excerpt (pin names and nets, part order shuffled) for the footprints in the layout excerpt that follows; sources: Cadence DE-HDL packaged netlist, KiCad conversion of 04192023_DAF0TMB3IC0_F0TG_MB_C_brd_V02_OCP.brd

C2541  Q_CAP  22UF 4V 20% X6S  pkg C0402  page 70 : A = PVDDCR_SOC_P0 ; B = GND
C6677  Q_CAP_DIFFBUS  DIFF BUS_0.22UF 6.3V 20% X6S  pkg C0201  page 330 : \1\ = P5E_CPU1_P1_TX_BUF_C_DP<8> ; \2\ = P5E_CPU1_P1_TX_BUF_DP<8>
PR92  Q_RES  0 5% CHIP  pkg 0402LF  page 202 : A = PVDDCR_CPU1_P0_VOS3 ; B = PVDDCR_CPU1_P0

(kicad_pcb
	(version 20260206)
	(generator "pcbnew")
	(generator_version "10.0")
	(general
		(thickness 1.6)
		(legacy_teardrops no)
	)
	(paper "A4")
	(title_block
		(title "04192023_DAF0TMB3IC0_F0TG_MB_C_brd_V02_OCP.brd")
		(comment 1 "Grand Teton / footprints 7668-7670 of 8354")
	)
	(layers
		(0 "F.Cu" signal "TOP")
		(4 "In1.Cu" signal "GND")
		(6 "In2.Cu" signal "IN1")
		(8 "In3.Cu" signal "GND1")
		(10 "In4.Cu" signal "IN2")
		(12 "In5.Cu" signal "GND2")
		(14 "In6.Cu" signal "IN3")
		(16 "In7.Cu" signal "GND3")
		(18 "In8.Cu" signal "VCC")
		(20 "In9.Cu" signal "VCC1")
		(22 "In10.Cu" signal "GND4")
		(24 "In11.Cu" signal "IN4")
		(26 "In12.Cu" signal "GND5")
		(28 "In13.Cu" signal "IN5")
		(30 "In14.Cu" signal "GND6")
		(32 "In15.Cu" signal "IN6")
		(34 "In16.Cu" signal "GND7")
		(2 "B.Cu" signal "BOTTOM")
		(9 "F.Adhes" user "F.Adhesive")
		(11 "B.Adhes" user "B.Adhesive")
		(13 "F.Paste" user "Package Geometry/Pastemask Top")
		(15 "B.Paste" user "Package Geometry/Pastemask Bottom")
		(5 "F.SilkS" user "Ref Des/Silkscreen Top")
		(7 "B.SilkS" user "Ref Des/Silkscreen Bottom")
		(1 "F.Mask" user "Board Geometry/Soldermask Top")
		(3 "B.Mask" user "Board Geometry/Soldermask Bottom")
		(17 "Dwgs.User" user "User.Drawings")
		(19 "Cmts.User" user "User.Comments")
		(21 "Eco1.User" user "User.Eco1")
		(23 "Eco2.User" user "User.Eco2")
		(25 "Edge.Cuts" user "Board Geometry/Outline")
		(27 "Margin" user)
		(31 "F.CrtYd" user "Package Geometry/Place Bound Top")
		(29 "B.CrtYd" user "Package Geometry/Place Bound Bottom")
		(35 "F.Fab" user "Ref Des/Assembly Top")
		(33 "B.Fab" user "Ref Des/Assembly Bottom")
	)
	(footprint ""
		(layer "B.Cu")
		(at 314.68441 -337.660488 -90)
		(property "Reference" "PR92"
			(at 0 0 90)
			(layer "B.SilkS")
			(hide yes)
			(effects
				(font
					(size 1.27 1.27)
				)
				(justify mirror)
			)
		)
		(property "Value" ""
			(at 0 0 90)
			(layer "B.Fab")
			(effects
				(font
					(size 1.27 1.27)
				)
				(justify mirror)
			)
		)
		(duplicate_pad_numbers_are_jumpers no)
		(fp_line
			(start -0.7874 0.4064)
			(end 0.7874 0.4064)
			(stroke
				(width 0.1524)
				(type default)
			)
			(layer "B.SilkS")
		)
		(fp_line
			(start 0.7874 0.4064)
			(end 0.7874 -0.4064)
			(stroke
				(width 0.1524)
				(type default)
			)
			(layer "B.SilkS")
		)
		(fp_line
			(start -0.7874 -0.4064)
			(end -0.7874 0.4064)
			(stroke
				(width 0.1524)
				(type default)
			)
			(layer "B.SilkS")
		)
		(fp_line
			(start 0.7874 -0.4064)
			(end -0.7874 -0.4064)
			(stroke
				(width 0.1524)
				(type default)
			)
			(layer "B.SilkS")
		)
		(fp_line
			(start -0.67945 0.3048)
			(end -0.120396 0.3048)
			(stroke
				(width 0.1)
				(type default)
			)
			(layer "B.Fab")
		)
		(fp_line
			(start -0.120396 0.3048)
			(end -0.120396 0.2794)
			(stroke
				(width 0.1)
				(type default)
			)
			(layer "B.Fab")
		)
		(fp_line
			(start 0.12065 0.3048)
			(end 0.67945 0.3048)
			(stroke
				(width 0.1)
				(type default)
			)
			(layer "B.Fab")
		)
		(fp_line
			(start 0.67945 0.3048)
			(end 0.67945 -0.305054)
			(stroke
				(width 0.1)
				(type default)
			)
			(layer "B.Fab")
		)
		(fp_line
			(start -0.120396 0.2794)
			(end 0.12065 0.2794)
			(stroke
				(width 0.1)
				(type default)
			)
			(layer "B.Fab")
		)
		(fp_line
			(start 0.12065 0.2794)
			(end 0.12065 0.3048)
			(stroke
				(width 0.1)
				(type default)
			)
			(layer "B.Fab")
		)
		(fp_line
			(start -0.12065 -0.2794)
			(end -0.12065 -0.3048)
			(stroke
				(width 0.1)
				(type default)
			)
			(layer "B.Fab")
		)
		(fp_line
			(start 0.12065 -0.2794)
			(end -0.12065 -0.2794)
			(stroke
				(width 0.1)
				(type default)
			)
			(layer "B.Fab")
		)
		(fp_line
			(start -0.67945 -0.3048)
			(end -0.67945 0.3048)
			(stroke
				(width 0.1)
				(type default)
			)
			(layer "B.Fab")
		)
		(fp_line
			(start -0.12065 -0.3048)
			(end -0.67945 -0.3048)
			(stroke
				(width 0.1)
				(type default)
			)
			(layer "B.Fab")
		)
		(fp_line
			(start 0.12065 -0.305054)
			(end 0.12065 -0.2794)
			(stroke
				(width 0.1)
				(type default)
			)
			(layer "B.Fab")
		)
		(fp_line
			(start 0.67945 -0.305054)
			(end 0.12065 -0.305054)
			(stroke
				(width 0.1)
				(type default)
			)
			(layer "B.Fab")
		)
		(pad "1" smd circle
			(at 0.40005 0 90)
			(size 0 0)
			(layers "B.Cu" "B.Mask" "B.Paste")
			(net "PVDDCR_CPU1_P0_VOS3")
		)
		(pad "2" smd circle
			(at -0.40005 0 90)
			(size 0 0)
			(layers "B.Cu" "B.Mask" "B.Paste")
			(net "PVDDCR_CPU1_P0")
		)
	)
	(footprint ""
		(layer "B.Cu")
		(at 365.328454 -251.78131)
		(property "Reference" "C2541"
			(at 0 0 0)
			(layer "B.SilkS")
			(hide yes)
			(effects
				(font
					(size 1.27 1.27)
				)
				(justify mirror)
			)
		)
		(property "Value" ""
			(at 0 0 0)
			(layer "B.Fab")
			(effects
				(font
					(size 1.27 1.27)
				)
				(justify mirror)
			)
		)
		(duplicate_pad_numbers_are_jumpers no)
		(fp_line
			(start -0.7874 -0.4064)
			(end -0.7874 0.4064)
			(stroke
				(width 0.1524)
				(type default)
			)
			(layer "B.SilkS")
		)
		(fp_line
			(start -0.7874 0.4064)
			(end 0.7874 0.4064)
			(stroke
				(width 0.1524)
				(type default)
			)
			(layer "B.SilkS")
		)
		(fp_line
			(start 0.7874 -0.4064)
			(end -0.7874 -0.4064)
			(stroke
				(width 0.1524)
				(type default)
			)
			(layer "B.SilkS")
		)
		(fp_line
			(start 0.7874 0.4064)
			(end 0.7874 -0.4064)
			(stroke
				(width 0.1524)
				(type default)
			)
			(layer "B.SilkS")
		)
		(fp_line
			(start -0.67945 -0.3048)
			(end -0.67945 0.3048)
			(stroke
				(width 0.1)
				(type default)
			)
			(layer "B.Fab")
		)
		(fp_line
			(start -0.67945 0.3048)
			(end -0.120396 0.3048)
			(stroke
				(width 0.1)
				(type default)
			)
			(layer "B.Fab")
		)
		(fp_line
			(start -0.12065 -0.3048)
			(end -0.67945 -0.3048)
			(stroke
				(width 0.1)
				(type default)
			)
			(layer "B.Fab")
		)
		(fp_line
			(start -0.12065 -0.2794)
			(end -0.12065 -0.3048)
			(stroke
				(width 0.1)
				(type default)
			)
			(layer "B.Fab")
		)
		(fp_line
			(start -0.120396 0.2794)
			(end 0.12065 0.2794)
			(stroke
				(width 0.1)
				(type default)
			)
			(layer "B.Fab")
		)
		(fp_line
			(start -0.120396 0.3048)
			(end -0.120396 0.2794)
			(stroke
				(width 0.1)
				(type default)
			)
			(layer "B.Fab")
		)
		(fp_line
			(start 0.12065 -0.305054)
			(end 0.12065 -0.2794)
			(stroke
				(width 0.1)
				(type default)
			)
			(layer "B.Fab")
		)
		(fp_line
			(start 0.12065 -0.2794)
			(end -0.12065 -0.2794)
			(stroke
				(width 0.1)
				(type default)
			)
			(layer "B.Fab")
		)
		(fp_line
			(start 0.12065 0.2794)
			(end 0.12065 0.3048)
			(stroke
				(width 0.1)
				(type default)
			)
			(layer "B.Fab")
		)
		(fp_line
			(start 0.12065 0.3048)
			(end 0.67945 0.3048)
			(stroke
				(width 0.1)
				(type default)
			)
			(layer "B.Fab")
		)
		(fp_line
			(start 0.67945 -0.305054)
			(end 0.12065 -0.305054)
			(stroke
				(width 0.1)
				(type default)
			)
			(layer "B.Fab")
		)
		(fp_line
			(start 0.67945 0.3048)
			(end 0.67945 -0.305054)
			(stroke
				(width 0.1)
				(type default)
			)
			(layer "B.Fab")
		)
		(pad "1" smd circle
			(at 0.40005 0 180)
			(size 0 0)
			(layers "B.Cu" "B.Mask" "B.Paste")
			(net "PVDDCR_SOC_P0")
		)
		(pad "2" smd circle
			(at -0.40005 0 180)
			(size 0 0)
			(layers "B.Cu" "B.Mask" "B.Paste")
			(net "GND")
		)
	)
	(footprint ""
		(layer "B.Cu")
		(at 74.720704 -408.517344 90)
		(property "Reference" "C6677"
			(at 0 0 90)
			(layer "B.SilkS")
			(hide yes)
			(effects
				(font
					(size 1.27 1.27)
				)
				(justify mirror)
			)
		)
		(property "Value" ""
			(at 0 0 90)
			(layer "B.Fab")
			(effects
				(font
					(size 1.27 1.27)
				)
				(justify mirror)
			)
		)
		(duplicate_pad_numbers_are_jumpers no)
		(fp_line
			(start 0.299974 -0.150114)
			(end -0.299974 -0.150114)
			(stroke
				(width 0.1)
				(type default)
			)
			(layer "B.Fab")
		)
		(fp_line
			(start -0.299974 -0.150114)
			(end -0.299974 0.150114)
			(stroke
				(width 0.1)
				(type default)
			)
			(layer "B.Fab")
		)
		(fp_line
			(start 0.299974 0.150114)
			(end 0.299974 -0.150114)
			(stroke
				(width 0.1)
				(type default)
			)
			(layer "B.Fab")
		)
		(fp_line
			(start -0.299974 0.150114)
			(end 0.299974 0.150114)
			(stroke
				(width 0.1)
				(type default)
			)
			(layer "B.Fab")
		)
		(pad "1" smd rect
			(at 0.2667 0 270)
			(size 0.3048 0.381)
			(layers "B.Cu" "B.Mask" "B.Paste")
			(net "P5E_CPU1_P1_TX_BUF_C_DP<8>")
		)
		(pad "2" smd rect
			(at -0.2667 0 270)
			(size 0.3048 0.381)
			(layers "B.Cu" "B.Mask" "B.Paste")
			(net "P5E_CPU1_P1_TX_BUF_DP<8>")
		)
	)
)
